(kicad_pcb
	(version 20260206)
	(generator "pcbnew")
	(generator_version "10.0")
	(general
		(thickness 1.6)
		(legacy_teardrops no)
	)
	(paper "A4")
	(title_block
		(title "Bryce Canyon_IOM_IOC_16318-2_OCP.brd")
		(comment 1 "Bryce Canyon / footprint 780 of 1605 (EXT2), pads 1-43 of 43")
	)
	(layers
		(0 "F.Cu" signal "TOP")
		(4 "In1.Cu" signal "L2GND")
		(6 "In2.Cu" signal "L3")
		(8 "In3.Cu" signal "L4VCC")
		(10 "In4.Cu" signal "L5VCC")
		(12 "In5.Cu" signal "L6")
		(14 "In6.Cu" signal "L7GND")
		(2 "B.Cu" signal "BOTTOM")
		(9 "F.Adhes" user "F.Adhesive")
		(11 "B.Adhes" user "B.Adhesive")
		(13 "F.Paste" user "Package Geometry/Pastemask Top")
		(15 "B.Paste" user "Package Geometry/Pastemask Bottom")
		(5 "F.SilkS" user "Ref Des/Silkscreen Top")
		(7 "B.SilkS" user "Ref Des/Silkscreen Bottom")
		(1 "F.Mask" user "Board Geometry/Soldermask Top")
		(3 "B.Mask" user "Board Geometry/Soldermask Bottom")
		(17 "Dwgs.User" user "User.Drawings")
		(19 "Cmts.User" user "User.Comments")
		(21 "Eco1.User" user "User.Eco1")
		(23 "Eco2.User" user "User.Eco2")
		(25 "Edge.Cuts" user "Board Geometry/Outline")
		(27 "Margin" user)
		(31 "F.CrtYd" user "Package Geometry/Place Bound Top")
		(29 "B.CrtYd" user "Package Geometry/Place Bound Bottom")
		(35 "F.Fab" user "Ref Des/Assembly Top")
		(33 "B.Fab" user "Ref Des/Assembly Bottom")
	)
	(footprint ""
		(layer "F.Cu")
		(at 159.999934 -14.699996)
		(property "Reference" "EXT2"
			(at 0 0 0)
			(layer "F.SilkS")
			(hide yes)
			(effects
				(font
					(size 1.27 1.27)
				)
			)
		)
		(property "Value" "MINI-SAS-36P-7-GP"
			(at -9.3345 2.159 0)
			(unlocked yes)
			(layer "F.Fab")
			(hide yes)
			(effects
				(font
					(size 1.016 1.016)
					(thickness 0.1524)
				)
			)
		)
		(property "Device Type" "PREFIT-42P-131384H522"
			(at -9.3345 0.635 0)
			(unlocked yes)
			(layer "F.Fab")
			(hide yes)
			(effects
				(font
					(size 1.016 1.016)
					(thickness 0.1524)
				)
			)
		)
		(duplicate_pad_numbers_are_jumpers no)
		(pad "A1" thru_hole circle
			(at -2.999994 -4.400042)
			(size 0.7366 0.7366)
			(drill 0.369824)
			(layers "*.Cu" "*.Mask")
			(remove_unused_layers no)
			(net "ZDEF_EXTB_TP_A1")
			(clearance 0.1778)
			(thermal_gap 0.1778)
		)
		(pad "A2" thru_hole circle
			(at -2.249932 -2.999994)
			(size 0.7366 0.7366)
			(drill 0.369824)
			(layers "*.Cu" "*.Mask")
			(remove_unused_layers no)
			(net "ZDEF_EXTB_TP_A2")
			(clearance 0.1778)
			(thermal_gap 0.1778)
		)
		(pad "A3" thru_hole circle
			(at -1.500124 -3.700018)
			(size 0.7366 0.7366)
			(drill 0.369824)
			(layers "*.Cu" "*.Mask")
			(remove_unused_layers no)
			(net "GND")
			(clearance 0.1778)
			(thermal_gap 0.1778)
		)
		(pad "A4" thru_hole circle
			(at -0.749808 -4.400042)
			(size 0.7366 0.7366)
			(drill 0.369824)
			(layers "*.Cu" "*.Mask")
			(remove_unused_layers no)
			(net "PHY_CON_B_TO_IOC_1_DP_C")
			(clearance 0.1778)
			(thermal_gap 0.1778)
		)
		(pad "A5" thru_hole circle
			(at 0 -2.999994)
			(size 0.7366 0.7366)
			(drill 0.369824)
			(layers "*.Cu" "*.Mask")
			(remove_unused_layers no)
			(net "PHY_CON_B_TO_IOC_1_DN_C")
			(clearance 0.1778)
			(thermal_gap 0.1778)
		)
		(pad "A6" thru_hole circle
			(at 0.749808 -3.700018)
			(size 0.7366 0.7366)
			(drill 0.369824)
			(layers "*.Cu" "*.Mask")
			(remove_unused_layers no)
			(net "GND")
			(clearance 0.1778)
			(thermal_gap 0.1778)
		)
		(pad "A7" thru_hole circle
			(at 1.500124 -4.400042)
			(size 0.7366 0.7366)
			(drill 0.369824)
			(layers "*.Cu" "*.Mask")
			(remove_unused_layers no)
			(net "PHY_CON_B_TO_IOC_0_DP_C")
			(clearance 0.1778)
			(thermal_gap 0.1778)
		)
		(pad "A8" thru_hole circle
			(at 2.250186 -2.999994)
			(size 0.7366 0.7366)
			(drill 0.369824)
			(layers "*.Cu" "*.Mask")
			(remove_unused_layers no)
			(net "PHY_CON_B_TO_IOC_0_DN_C")
			(clearance 0.1778)
			(thermal_gap 0.1778)
		)
		(pad "A9" thru_hole circle
			(at 2.999994 -3.700018)
			(size 0.7366 0.7366)
			(drill 0.369824)
			(layers "*.Cu" "*.Mask")
			(remove_unused_layers no)
			(net "GND")
			(clearance 0.1778)
			(thermal_gap 0.1778)
		)
		(pad "B1" thru_hole circle
			(at -2.999994 -8.199882)
			(size 0.7366 0.7366)
			(drill 0.369824)
			(layers "*.Cu" "*.Mask")
			(remove_unused_layers no)
			(net "ZDEF_EXTB_TP_B1")
			(clearance 0.1778)
			(thermal_gap 0.1778)
		)
		(pad "B2" thru_hole circle
			(at -2.249932 -6.800088)
			(size 0.7366 0.7366)
			(drill 0.369824)
			(layers "*.Cu" "*.Mask")
			(remove_unused_layers no)
			(net "ZDEF_EXTB_TP_B2")
			(clearance 0.1778)
			(thermal_gap 0.1778)
		)
		(pad "B3" thru_hole circle
			(at -1.500124 -7.500112)
			(size 0.7366 0.7366)
			(drill 0.369824)
			(layers "*.Cu" "*.Mask")
			(remove_unused_layers no)
			(net "GND")
			(clearance 0.1778)
			(thermal_gap 0.1778)
		)
		(pad "B4" thru_hole circle
			(at -0.749808 -8.199882)
			(size 0.7366 0.7366)
			(drill 0.369824)
			(layers "*.Cu" "*.Mask")
			(remove_unused_layers no)
			(net "PHY_CON_B_TO_IOC_3_DP_C")
			(clearance 0.1778)
			(thermal_gap 0.1778)
		)
		(pad "B5" thru_hole circle
			(at 0 -6.800088)
			(size 0.7366 0.7366)
			(drill 0.369824)
			(layers "*.Cu" "*.Mask")
			(remove_unused_layers no)
			(net "PHY_CON_B_TO_IOC_3_DN_C")
			(clearance 0.1778)
			(thermal_gap 0.1778)
		)
		(pad "B6" thru_hole circle
			(at 0.749808 -7.500112)
			(size 0.7366 0.7366)
			(drill 0.369824)
			(layers "*.Cu" "*.Mask")
			(remove_unused_layers no)
			(net "GND")
			(clearance 0.1778)
			(thermal_gap 0.1778)
		)
		(pad "B7" thru_hole circle
			(at 1.500124 -8.199882)
			(size 0.7366 0.7366)
			(drill 0.369824)
			(layers "*.Cu" "*.Mask")
			(remove_unused_layers no)
			(net "PHY_CON_B_TO_IOC_2_DP_C")
			(clearance 0.1778)
			(thermal_gap 0.1778)
		)
		(pad "B8" thru_hole circle
			(at 2.250186 -6.800088)
			(size 0.7366 0.7366)
			(drill 0.369824)
			(layers "*.Cu" "*.Mask")
			(remove_unused_layers no)
			(net "PHY_CON_B_TO_IOC_2_DN_C")
			(clearance 0.1778)
			(thermal_gap 0.1778)
		)
		(pad "B9" thru_hole circle
			(at 2.999994 -7.500112)
			(size 0.7366 0.7366)
			(drill 0.369824)
			(layers "*.Cu" "*.Mask")
			(remove_unused_layers no)
			(net "GND")
			(clearance 0.1778)
			(thermal_gap 0.1778)
		)
		(pad "C1" thru_hole circle
			(at -2.999994 -11.999976)
			(size 0.7366 0.7366)
			(drill 0.369824)
			(layers "*.Cu" "*.Mask")
			(remove_unused_layers no)
			(net "ZDEF_EXTB_TP_C1")
			(clearance 0.1778)
			(thermal_gap 0.1778)
		)
		(pad "C2" thru_hole circle
			(at -2.249932 -10.599928)
			(size 0.7366 0.7366)
			(drill 0.369824)
			(layers "*.Cu" "*.Mask")
			(remove_unused_layers no)
			(net "ZDEF_EXTB_TP_C2")
			(clearance 0.1778)
			(thermal_gap 0.1778)
		)
		(pad "C3" thru_hole circle
			(at -1.500124 -11.299952)
			(size 0.7366 0.7366)
			(drill 0.369824)
			(layers "*.Cu" "*.Mask")
			(remove_unused_layers no)
			(net "GND")
			(clearance 0.1778)
			(thermal_gap 0.1778)
		)
		(pad "C4" thru_hole circle
			(at -0.749808 -11.999976)
			(size 0.7366 0.7366)
			(drill 0.369824)
			(layers "*.Cu" "*.Mask")
			(remove_unused_layers no)
			(net "PHY_IOC_TO_CON_B_1_DP")
			(clearance 0.1778)
			(thermal_gap 0.1778)
		)
		(pad "C5" thru_hole circle
			(at 0 -10.599928)
			(size 0.7366 0.7366)
			(drill 0.369824)
			(layers "*.Cu" "*.Mask")
			(remove_unused_layers no)
			(net "PHY_IOC_TO_CON_B_1_DN")
			(clearance 0.1778)
			(thermal_gap 0.1778)
		)
		(pad "C6" thru_hole circle
			(at 0.749808 -11.299952)
			(size 0.7366 0.7366)
			(drill 0.369824)
			(layers "*.Cu" "*.Mask")
			(remove_unused_layers no)
			(net "GND")
			(clearance 0.1778)
			(thermal_gap 0.1778)
		)
		(pad "C7" thru_hole circle
			(at 1.500124 -11.999976)
			(size 0.7366 0.7366)
			(drill 0.369824)
			(layers "*.Cu" "*.Mask")
			(remove_unused_layers no)
			(net "PHY_IOC_TO_CON_B_0_DP")
			(clearance 0.1778)
			(thermal_gap 0.1778)
		)
		(pad "C8" thru_hole circle
			(at 2.250186 -10.599928)
			(size 0.7366 0.7366)
			(drill 0.369824)
			(layers "*.Cu" "*.Mask")
			(remove_unused_layers no)
			(net "PHY_IOC_TO_CON_B_0_DN")
			(clearance 0.1778)
			(thermal_gap 0.1778)
		)
		(pad "C9" thru_hole circle
			(at 2.999994 -11.299952)
			(size 0.7366 0.7366)
			(drill 0.369824)
			(layers "*.Cu" "*.Mask")
			(remove_unused_layers no)
			(net "GND")
			(clearance 0.1778)
			(thermal_gap 0.1778)
		)
		(pad "D1" thru_hole circle
			(at -2.999994 -15.80007)
			(size 0.7366 0.7366)
			(drill 0.369824)
			(layers "*.Cu" "*.Mask")
			(remove_unused_layers no)
			(net "ZDEF_EXTB_TP_D1")
			(clearance 0.1778)
			(thermal_gap 0.1778)
		)
		(pad "D2" thru_hole circle
			(at -2.249932 -14.400022)
			(size 0.7366 0.7366)
			(drill 0.369824)
			(layers "*.Cu" "*.Mask")
			(remove_unused_layers no)
			(net "ZDEF_EXTB_TP_D2")
			(clearance 0.1778)
			(thermal_gap 0.1778)
		)
		(pad "D3" thru_hole circle
			(at -1.500124 -15.100046)
			(size 0.7366 0.7366)
			(drill 0.369824)
			(layers "*.Cu" "*.Mask")
			(remove_unused_layers no)
			(net "GND")
			(clearance 0.1778)
			(thermal_gap 0.1778)
		)
		(pad "D4" thru_hole circle
			(at -0.749808 -15.80007)
			(size 0.7366 0.7366)
			(drill 0.369824)
			(layers "*.Cu" "*.Mask")
			(remove_unused_layers no)
			(net "PHY_IOC_TO_CON_B_3_DP")
			(clearance 0.1778)
			(thermal_gap 0.1778)
		)
		(pad "D5" thru_hole circle
			(at 0 -14.400022)
			(size 0.7366 0.7366)
			(drill 0.369824)
			(layers "*.Cu" "*.Mask")
			(remove_unused_layers no)
			(net "PHY_IOC_TO_CON_B_3_DN")
			(clearance 0.1778)
			(thermal_gap 0.1778)
		)
		(pad "D6" thru_hole circle
			(at 0.749808 -15.100046)
			(size 0.7366 0.7366)
			(drill 0.369824)
			(layers "*.Cu" "*.Mask")
			(remove_unused_layers no)
			(net "GND")
			(clearance 0.1778)
			(thermal_gap 0.1778)
		)
		(pad "D7" thru_hole circle
			(at 1.500124 -15.80007)
			(size 0.7366 0.7366)
			(drill 0.369824)
			(layers "*.Cu" "*.Mask")
			(remove_unused_layers no)
			(net "PHY_IOC_TO_CON_B_2_DP")
			(clearance 0.1778)
			(thermal_gap 0.1778)
		)
		(pad "D8" thru_hole circle
			(at 2.250186 -14.400022)
			(size 0.7366 0.7366)
			(drill 0.369824)
			(layers "*.Cu" "*.Mask")
			(remove_unused_layers no)
			(net "PHY_IOC_TO_CON_B_2_DN")
			(clearance 0.1778)
			(thermal_gap 0.1778)
		)
		(pad "D9" thru_hole circle
			(at 2.999994 -15.100046)
			(size 0.7366 0.7366)
			(drill 0.369824)
			(layers "*.Cu" "*.Mask")
			(remove_unused_layers no)
			(net "GND")
			(clearance 0.1778)
			(thermal_gap 0.1778)
		)
		(pad "G1" thru_hole circle
			(at -5.500116 9.61009)
			(size 0.9144 0.9144)
			(drill 0.569976)
			(layers "*.Cu" "*.Mask")
			(remove_unused_layers no)
			(net "EXT2_CONN_GND")
			(clearance 0.1905)
			(thermal_gap 0.1905)
		)
		(pad "G2" thru_hole circle
			(at 5.500116 9.61009)
			(size 0.9144 0.9144)
			(drill 0.569976)
			(layers "*.Cu" "*.Mask")
			(remove_unused_layers no)
			(net "EXT2_CONN_GND")
			(clearance 0.1905)
			(thermal_gap 0.1905)
		)
		(pad "G3" thru_hole circle
			(at -5.500116 -3.700018)
			(size 0.9144 0.9144)
			(drill 0.569976)
			(layers "*.Cu" "*.Mask")
			(remove_unused_layers no)
			(net "EXT2_CONN_GND")
			(clearance 0.1905)
			(thermal_gap 0.1905)
		)
		(pad "G4" thru_hole circle
			(at 5.500116 -3.700018)
			(size 0.9144 0.9144)
			(drill 0.569976)
			(layers "*.Cu" "*.Mask")
			(remove_unused_layers no)
			(net "EXT2_CONN_GND")
			(clearance 0.1905)
			(thermal_gap 0.1905)
		)
		(pad "G5" thru_hole circle
			(at -1.500124 -17.509998)
			(size 0.9144 0.9144)
			(drill 0.569976)
			(layers "*.Cu" "*.Mask")
			(remove_unused_layers no)
			(net "EXT2_CONN_GND")
			(clearance 0.1905)
			(thermal_gap 0.1905)
		)
		(pad "G6" thru_hole circle
			(at 2.999994 -17.509998)
			(size 0.9144 0.9144)
			(drill 0.569976)
			(layers "*.Cu" "*.Mask")
			(remove_unused_layers no)
			(net "EXT2_CONN_GND")
			(clearance 0.1905)
			(thermal_gap 0.1905)
		)
		(pad "G7" thru_hole circle
			(at 0 0)
			(size 3.81 3.81)
			(drill 2.2098)
			(layers "*.Cu" "*.Mask")
			(remove_unused_layers no)
			(net "EXT2_CONN_GND")
			(clearance -0.2921)
			(thermal_gap 0.3048)
			(padstack
				(mode front_inner_back)
				(layer "Inner"
					(shape circle)
					(size 2.6162 2.6162)
					(clearance 0.3048)
				)
				(layer "B.Cu"
					(shape circle)
					(size 3.81 3.81)
					(clearance -0.2921)
				)
			)
		)
	)
)
